# S9S_MB_2U (Grand Teton) — schematic netlist excerpt (pin names and nets, part order shuffled) for the footprints in the layout excerpt that follows; sources: Cadence DE-HDL packaged netlist, KiCad conversion of 03242023_DA0F0TMBIJ0_F0T_Motherboard_J_brd_V01_OCP.brd

PC1677  Q_CAP  22UF 16V 20% X6S  pkg C0805  page 289 : A = SW_P12V_PVCCFA_EHV_FIVRA_CPU1_L ; B = GND
R1799  Q_RES  7.87K 1% CHIP  pkg 0402LF  page 250 : A = P12V_AUX ; B = P12V_AUX_ADC
PC229_P0_7  Q_CAP  2.2UF 10V 10% X6S  pkg C0402  page 270 : A = PVCCIN_CPU0_PVCC ; B = GND

(kicad_pcb
	(version 20260206)
	(generator "pcbnew")
	(generator_version "10.0")
	(general
		(thickness 1.6)
		(legacy_teardrops no)
	)
	(paper "A4")
	(title_block
		(title "03242023_DA0F0TMBIJ0_F0T_Motherboard_J_brd_V01_OCP.brd")
		(comment 1 "Grand Teton / footprints 1733-1735 of 6105")
	)
	(layers
		(0 "F.Cu" signal "TOP")
		(4 "In1.Cu" signal "GND")
		(6 "In2.Cu" signal "IN1")
		(8 "In3.Cu" signal "GND1")
		(10 "In4.Cu" signal "IN2")
		(12 "In5.Cu" signal "GND2")
		(14 "In6.Cu" signal "IN3")
		(16 "In7.Cu" signal "GND3")
		(18 "In8.Cu" signal "VCC")
		(20 "In9.Cu" signal "VCC1")
		(22 "In10.Cu" signal "GND4")
		(24 "In11.Cu" signal "IN4")
		(26 "In12.Cu" signal "GND5")
		(28 "In13.Cu" signal "IN5")
		(30 "In14.Cu" signal "GND6")
		(32 "In15.Cu" signal "IN6")
		(34 "In16.Cu" signal "GND7")
		(2 "B.Cu" signal "BOTTOM")
		(9 "F.Adhes" user "F.Adhesive")
		(11 "B.Adhes" user "B.Adhesive")
		(13 "F.Paste" user "Package Geometry/Pastemask Top")
		(15 "B.Paste" user "Package Geometry/Pastemask Bottom")
		(5 "F.SilkS" user "Ref Des/Silkscreen Top")
		(7 "B.SilkS" user "Ref Des/Silkscreen Bottom")
		(1 "F.Mask" user "Board Geometry/Soldermask Top")
		(3 "B.Mask" user "Board Geometry/Soldermask Bottom")
		(17 "Dwgs.User" user "User.Drawings")
		(19 "Cmts.User" user "User.Comments")
		(21 "Eco1.User" user "User.Eco1")
		(23 "Eco2.User" user "User.Eco2")
		(25 "Edge.Cuts" user "Board Geometry/Outline")
		(27 "Margin" user)
		(31 "F.CrtYd" user "Package Geometry/Place Bound Top")
		(29 "B.CrtYd" user "Package Geometry/Place Bound Bottom")
		(35 "F.Fab" user "Ref Des/Assembly Top")
		(33 "B.Fab" user "Ref Des/Assembly Bottom")
	)
	(footprint ""
		(layer "F.Cu")
		(at 56.349138 -360.92765)
		(property "Reference" "PC1677"
			(at 0 0 0)
			(layer "F.SilkS")
			(hide yes)
			(effects
				(font
					(size 1.27 1.27)
				)
			)
		)
		(property "Value" ""
			(at 0 0 0)
			(layer "F.Fab")
			(effects
				(font
					(size 1.27 1.27)
				)
			)
		)
		(duplicate_pad_numbers_are_jumpers no)
		(fp_line
			(start -1.524 -0.762)
			(end 1.524 -0.762)
			(stroke
				(width 0.1524)
				(type default)
			)
			(layer "F.SilkS")
		)
		(fp_line
			(start -1.524 0.762)
			(end -1.524 -0.762)
			(stroke
				(width 0.1524)
				(type default)
			)
			(layer "F.SilkS")
		)
		(fp_line
			(start 1.524 -0.762)
			(end 1.524 0.762)
			(stroke
				(width 0.1524)
				(type default)
			)
			(layer "F.SilkS")
		)
		(fp_line
			(start 1.524 0.762)
			(end -1.524 0.762)
			(stroke
				(width 0.1524)
				(type default)
			)
			(layer "F.SilkS")
		)
		(fp_line
			(start -1.1049 -0.724916)
			(end -1.1049 0.724916)
			(stroke
				(width 0.1)
				(type default)
			)
			(layer "F.Fab")
		)
		(fp_line
			(start -1.1049 0.724916)
			(end 1.1049 0.724916)
			(stroke
				(width 0.1)
				(type default)
			)
			(layer "F.Fab")
		)
		(fp_line
			(start 1.1049 -0.724916)
			(end -1.1049 -0.724916)
			(stroke
				(width 0.1)
				(type default)
			)
			(layer "F.Fab")
		)
		(fp_line
			(start 1.1049 0.724916)
			(end 1.1049 -0.724916)
			(stroke
				(width 0.1)
				(type default)
			)
			(layer "F.Fab")
		)
		(pad "1" smd rect
			(at -0.889 0 180)
			(size 1.016 1.27)
			(layers "F.Cu" "F.Mask" "F.Paste")
			(net "SW_P12V_PVCCFA_EHV_FIVRA_CPU1_L")
		)
		(pad "2" smd rect
			(at 0.889 0 180)
			(size 1.016 1.27)
			(layers "F.Cu" "F.Mask" "F.Paste")
			(net "GND")
		)
	)
	(footprint ""
		(layer "F.Cu")
		(at 46.582584 -112.619282 180)
		(property "Reference" "R1799"
			(at 0 0 180)
			(layer "F.SilkS")
			(hide yes)
			(effects
				(font
					(size 1.27 1.27)
				)
			)
		)
		(property "Value" ""
			(at 0 0 180)
			(layer "F.Fab")
			(effects
				(font
					(size 1.27 1.27)
				)
			)
		)
		(duplicate_pad_numbers_are_jumpers no)
		(fp_line
			(start 0.7874 0.4064)
			(end -0.7874 0.4064)
			(stroke
				(width 0.1524)
				(type default)
			)
			(layer "F.SilkS")
		)
		(fp_line
			(start 0.7874 -0.4064)
			(end 0.7874 0.4064)
			(stroke
				(width 0.1524)
				(type default)
			)
			(layer "F.SilkS")
		)
		(fp_line
			(start -0.7874 0.4064)
			(end -0.7874 -0.4064)
			(stroke
				(width 0.1524)
				(type default)
			)
			(layer "F.SilkS")
		)
		(fp_line
			(start -0.7874 -0.4064)
			(end 0.7874 -0.4064)
			(stroke
				(width 0.1524)
				(type default)
			)
			(layer "F.SilkS")
		)
		(fp_line
			(start 0.67945 0.3048)
			(end 0.120396 0.3048)
			(stroke
				(width 0.1)
				(type default)
			)
			(layer "F.Fab")
		)
		(fp_line
			(start 0.67945 -0.3048)
			(end 0.67945 0.3048)
			(stroke
				(width 0.1)
				(type default)
			)
			(layer "F.Fab")
		)
		(fp_line
			(start 0.12065 -0.2794)
			(end 0.12065 -0.3048)
			(stroke
				(width 0.1)
				(type default)
			)
			(layer "F.Fab")
		)
		(fp_line
			(start 0.12065 -0.3048)
			(end 0.67945 -0.3048)
			(stroke
				(width 0.1)
				(type default)
			)
			(layer "F.Fab")
		)
		(fp_line
			(start 0.120396 0.3048)
			(end 0.120396 0.2794)
			(stroke
				(width 0.1)
				(type default)
			)
			(layer "F.Fab")
		)
		(fp_line
			(start 0.120396 0.2794)
			(end -0.12065 0.2794)
			(stroke
				(width 0.1)
				(type default)
			)
			(layer "F.Fab")
		)
		(fp_line
			(start -0.12065 0.3048)
			(end -0.67945 0.3048)
			(stroke
				(width 0.1)
				(type default)
			)
			(layer "F.Fab")
		)
		(fp_line
			(start -0.12065 0.2794)
			(end -0.12065 0.3048)
			(stroke
				(width 0.1)
				(type default)
			)
			(layer "F.Fab")
		)
		(fp_line
			(start -0.12065 -0.2794)
			(end 0.12065 -0.2794)
			(stroke
				(width 0.1)
				(type default)
			)
			(layer "F.Fab")
		)
		(fp_line
			(start -0.12065 -0.305054)
			(end -0.12065 -0.2794)
			(stroke
				(width 0.1)
				(type default)
			)
			(layer "F.Fab")
		)
		(fp_line
			(start -0.67945 0.3048)
			(end -0.67945 -0.305054)
			(stroke
				(width 0.1)
				(type default)
			)
			(layer "F.Fab")
		)
		(fp_line
			(start -0.67945 -0.305054)
			(end -0.12065 -0.305054)
			(stroke
				(width 0.1)
				(type default)
			)
			(layer "F.Fab")
		)
		(pad "1" smd circle
			(at -0.40005 0 180)
			(size 0 0)
			(layers "F.Cu" "F.Mask" "F.Paste")
			(net "P12V_AUX")
		)
		(pad "2" smd circle
			(at 0.40005 0 180)
			(size 0 0)
			(layers "F.Cu" "F.Mask" "F.Paste")
			(net "P12V_AUX_ADC")
		)
	)
	(footprint ""
		(layer "F.Cu")
		(at 325.072248 -342.786208 -90)
		(property "Reference" "PC229_P0_7"
			(at 0 0 270)
			(layer "F.SilkS")
			(hide yes)
			(effects
				(font
					(size 1.27 1.27)
				)
			)
		)
		(property "Value" ""
			(at 0 0 270)
			(layer "F.Fab")
			(effects
				(font
					(size 1.27 1.27)
				)
			)
		)
		(duplicate_pad_numbers_are_jumpers no)
		(fp_line
			(start -0.7874 0.4064)
			(end -0.7874 -0.4064)
			(stroke
				(width 0.1524)
				(type default)
			)
			(layer "F.SilkS")
		)
		(fp_line
			(start 0.7874 0.4064)
			(end -0.7874 0.4064)
			(stroke
				(width 0.1524)
				(type default)
			)
			(layer "F.SilkS")
		)
		(fp_line
			(start -0.7874 -0.4064)
			(end 0.7874 -0.4064)
			(stroke
				(width 0.1524)
				(type default)
			)
			(layer "F.SilkS")
		)
		(fp_line
			(start 0.7874 -0.4064)
			(end 0.7874 0.4064)
			(stroke
				(width 0.1524)
				(type default)
			)
			(layer "F.SilkS")
		)
		(fp_line
			(start -0.67945 0.3048)
			(end -0.67945 -0.305054)
			(stroke
				(width 0.1)
				(type default)
			)
			(layer "F.Fab")
		)
		(fp_line
			(start -0.12065 0.3048)
			(end -0.67945 0.3048)
			(stroke
				(width 0.1)
				(type default)
			)
			(layer "F.Fab")
		)
		(fp_line
			(start 0.120396 0.3048)
			(end 0.120396 0.2794)
			(stroke
				(width 0.1)
				(type default)
			)
			(layer "F.Fab")
		)
		(fp_line
			(start 0.67945 0.3048)
			(end 0.120396 0.3048)
			(stroke
				(width 0.1)
				(type default)
			)
			(layer "F.Fab")
		)
		(fp_line
			(start -0.12065 0.2794)
			(end -0.12065 0.3048)
			(stroke
				(width 0.1)
				(type default)
			)
			(layer "F.Fab")
		)
		(fp_line
			(start 0.120396 0.2794)
			(end -0.12065 0.2794)
			(stroke
				(width 0.1)
				(type default)
			)
			(layer "F.Fab")
		)
		(fp_line
			(start -0.12065 -0.2794)
			(end 0.12065 -0.2794)
			(stroke
				(width 0.1)
				(type default)
			)
			(layer "F.Fab")
		)
		(fp_line
			(start 0.12065 -0.2794)
			(end 0.12065 -0.3048)
			(stroke
				(width 0.1)
				(type default)
			)
			(layer "F.Fab")
		)
		(fp_line
			(start 0.12065 -0.3048)
			(end 0.67945 -0.3048)
			(stroke
				(width 0.1)
				(type default)
			)
			(layer "F.Fab")
		)
		(fp_line
			(start 0.67945 -0.3048)
			(end 0.67945 0.3048)
			(stroke
				(width 0.1)
				(type default)
			)
			(layer "F.Fab")
		)
		(fp_line
			(start -0.67945 -0.305054)
			(end -0.12065 -0.305054)
			(stroke
				(width 0.1)
				(type default)
			)
			(layer "F.Fab")
		)
		(fp_line
			(start -0.12065 -0.305054)
			(end -0.12065 -0.2794)
			(stroke
				(width 0.1)
				(type default)
			)
			(layer "F.Fab")
		)
		(pad "1" smd circle
			(at -0.40005 0 270)
			(size 0 0)
			(layers "F.Cu" "F.Mask" "F.Paste")
			(net "PVCCIN_CPU0_PVCC")
		)
		(pad "2" smd circle
			(at 0.40005 0 270)
			(size 0 0)
			(layers "F.Cu" "F.Mask" "F.Paste")
			(net "GND")
		)
	)
)
